#ISCELL
  mstr_symbols design_note *
  *
#ISCELL
  mstr_symbols intel_corp_bpage *
  *
#ISCELL
  mstr_standard offpage *
  page172_i10
#ISCELL
  mstr_standard offpage *
  page172_i11
#ISCELL
  mstr_standard offpage *
  page172_i12
#ISCELL
  mstr_symbols gnd *
  page172_i35
#CELL
  mstr_discrete cap *
  page172_i36
#ISCELL
  mstr_symbols p12v *
  page172_i37
#CELL
  mstr_discrete cap *
  page172_i39
#ISCELL
  mstr_symbols gnd *
  page172_i40
#ISCELL
  mstr_symbols p5v *
  page172_i42
#CELL
  dev_discrete cap_a *
  page172_i5
#ISCELL
  mstr_symbols gnd *
  page172_i57
#ISCELL
  mstr_symbols gnd *
  page172_i58
#ISCELL
  mstr_symbols gnd *
  page172_i59
#CELL
  dev_discrete cap_a *
  page172_i6
#ISCELL
  mstr_symbols gnd *
  page172_i60
#ISCELL
  mstr_symbols gnd *
  page172_i61
#ISCELL
  mstr_symbols gnd *
  page172_i62
#ISCELL
  mstr_symbols gnd *
  page172_i63
#ISCELL
  mstr_symbols gnd *
  page172_i64
#CELL
  mstr_discrete fuse *
  page172_i66
#CELL
  w_hdl skt-sata7p-6p-165-gp-u1 *
  page172_i67
#CELL
  w_hdl skt-sata7p-6p-165-gp-u1 *
  page172_i68
#ISCELL
  mstr_symbols gnd *
  page172_i69
#CELL
  dev_discrete cap_a *
  page172_i7
#ISCELL
  mstr_symbols gnd *
  page172_i70
#CELL
  w_hdl fuse-3a75v-gp *
  page172_i71
#CELL
  dev_discrete cap_a *
  page172_i8
#ISCELL
  mstr_standard offpage *
  page172_i9
